(kicad_pcb
	(version 20260206)
	(generator "pcbnew")
	(generator_version "10.0")
	(general
		(thickness 1.6)
		(legacy_teardrops no)
	)
	(paper "A4")
	(title_block
		(title "04192023_DAF0TMB3IC0_F0TG_MB_C_brd_V02_OCP.brd")
		(comment 1 "Grand Teton / footprint 827 of 8354 (U6017), pads 112-223 of 354")
	)
	(layers
		(0 "F.Cu" signal "TOP")
		(4 "In1.Cu" signal "GND")
		(6 "In2.Cu" signal "IN1")
		(8 "In3.Cu" signal "GND1")
		(10 "In4.Cu" signal "IN2")
		(12 "In5.Cu" signal "GND2")
		(14 "In6.Cu" signal "IN3")
		(16 "In7.Cu" signal "GND3")
		(18 "In8.Cu" signal "VCC")
		(20 "In9.Cu" signal "VCC1")
		(22 "In10.Cu" signal "GND4")
		(24 "In11.Cu" signal "IN4")
		(26 "In12.Cu" signal "GND5")
		(28 "In13.Cu" signal "IN5")
		(30 "In14.Cu" signal "GND6")
		(32 "In15.Cu" signal "IN6")
		(34 "In16.Cu" signal "GND7")
		(2 "B.Cu" signal "BOTTOM")
		(9 "F.Adhes" user "F.Adhesive")
		(11 "B.Adhes" user "B.Adhesive")
		(13 "F.Paste" user "Package Geometry/Pastemask Top")
		(15 "B.Paste" user "Package Geometry/Pastemask Bottom")
		(5 "F.SilkS" user "Ref Des/Silkscreen Top")
		(7 "B.SilkS" user "Ref Des/Silkscreen Bottom")
		(1 "F.Mask" user "Board Geometry/Soldermask Top")
		(3 "B.Mask" user "Board Geometry/Soldermask Bottom")
		(17 "Dwgs.User" user "User.Drawings")
		(19 "Cmts.User" user "User.Comments")
		(21 "Eco1.User" user "User.Eco1")
		(23 "Eco2.User" user "User.Eco2")
		(25 "Edge.Cuts" user "Board Geometry/Outline")
		(27 "Margin" user)
		(31 "F.CrtYd" user "Package Geometry/Place Bound Top")
		(29 "B.CrtYd" user "Package Geometry/Place Bound Bottom")
		(35 "F.Fab" user "Ref Des/Assembly Top")
		(33 "B.Fab" user "Ref Des/Assembly Bottom")
	)
	(footprint ""
		(layer "F.Cu")
		(at 123.567952 -387.342634)
		(property "Reference" "U6017"
			(at -6.180074 -7.979664 0)
			(unlocked yes)
			(layer "F.SilkS")
			(effects
				(font
					(size 0.7874 0.5842)
					(thickness 0.1524)
				)
				(justify left)
			)
		)
		(property "Value" ""
			(at 0 0 0)
			(layer "F.Fab")
			(effects
				(font
					(size 1.27 1.27)
				)
			)
		)
		(duplicate_pad_numbers_are_jumpers no)
		(pad "BV32" smd circle
			(at 1.20269 2.724912)
			(size 0.381 0.381)
			(layers "F.Cu" "F.Mask" "F.Paste")
			(net "GND")
		)
		(pad "BW2" smd circle
			(at 1.150112 -3.41884)
			(size 0.3048 0.3048)
			(layers "F.Cu" "F.Mask" "F.Paste")
			(net "GND")
		)
		(pad "BW34" smd circle
			(at 1.150112 3.420364)
			(size 0.3048 0.3048)
			(layers "F.Cu" "F.Mask" "F.Paste")
			(net "GND")
		)
		(pad "BY1" smd oval
			(at 0.849884 -3.938524)
			(size 0.254 0.3302)
			(layers "F.Cu" "F.Mask" "F.Paste")
			(net "GND")
		)
		(pad "BY35" smd oval
			(at 0.849884 3.940048)
			(size 0.254 0.3302)
			(layers "F.Cu" "F.Mask" "F.Paste")
			(net "GND")
		)
		(pad "C2" smd circle
			(at 10.750042 -3.41884)
			(size 0.3048 0.3048)
			(layers "F.Cu" "F.Mask" "F.Paste")
			(net "NCF_CPU1_P3_GND")
		)
		(pad "C34" smd circle
			(at 10.750042 3.420364)
			(size 0.3048 0.3048)
			(layers "F.Cu" "F.Mask" "F.Paste")
			(net "NCF_CPU1_P3_GND")
		)
		(pad "CA7" smd circle
			(at 0.80264 -2.12471)
			(size 0.381 0.381)
			(layers "F.Cu" "F.Mask" "F.Paste")
			(net "P5E_CPU1_P3_TX_BUF_DP<8>")
		)
		(pad "CA26" smd circle
			(at 0.80264 1.339342)
			(size 0.381 0.381)
			(layers "F.Cu" "F.Mask" "F.Paste")
			(net "P5E_CPU1_P3_RX_DP<8>")
		)
		(pad "CB2" smd circle
			(at 0.54991 -3.41884)
			(size 0.3048 0.3048)
			(layers "F.Cu" "F.Mask" "F.Paste")
			(net "P5E_CPU1_P3_RX_BUF_DN<8>")
		)
		(pad "CB34" smd circle
			(at 0.54991 3.420364)
			(size 0.3048 0.3048)
			(layers "F.Cu" "F.Mask" "F.Paste")
			(net "P5E_CPU1_P3_TX_C_DN<8>")
		)
		(pad "CC10" smd circle
			(at 0.40259 -1.431798)
			(size 0.381 0.381)
			(layers "F.Cu" "F.Mask" "F.Paste")
			(net "P5E_CPU1_P3_TX_BUF_DN<8>")
		)
		(pad "CC29" smd circle
			(at 0.40259 2.032254)
			(size 0.381 0.381)
			(layers "F.Cu" "F.Mask" "F.Paste")
			(net "P5E_CPU1_P3_RX_DN<8>")
		)
		(pad "CD1" smd oval
			(at 0.249936 -3.938524)
			(size 0.254 0.3302)
			(layers "F.Cu" "F.Mask" "F.Paste")
			(net "P5E_CPU1_P3_RX_BUF_DP<8>")
		)
		(pad "CD35" smd oval
			(at 0.249936 3.940048)
			(size 0.254 0.3302)
			(layers "F.Cu" "F.Mask" "F.Paste")
			(net "P5E_CPU1_P3_TX_C_DP<8>")
		)
		(pad "CE4" smd circle
			(at 0.00254 -2.817368)
			(size 0.381 0.381)
			(layers "F.Cu" "F.Mask" "F.Paste")
			(net "GND")
		)
		(pad "CE13" smd circle
			(at 0.00254 -0.79629)
			(size 0.3048 0.3048)
			(layers "F.Cu" "F.Mask" "F.Paste")
			(net "GND")
		)
		(pad "CE17" smd circle
			(at 0.00254 -0.296164)
			(size 0.3048 0.3048)
			(layers "F.Cu" "F.Mask" "F.Paste")
			(net "P1V8_CPU1_RT3_1A")
		)
		(pad "CE20" smd circle
			(at 0.00254 0.203708)
			(size 0.3048 0.3048)
			(layers "F.Cu" "F.Mask" "F.Paste")
			(net "P1V8_CPU1_RT3_1A")
		)
		(pad "CE22" smd circle
			(at 0.00254 0.703834)
			(size 0.3048 0.3048)
			(layers "F.Cu" "F.Mask" "F.Paste")
			(net "GND")
		)
		(pad "CE32" smd circle
			(at 0.00254 2.724912)
			(size 0.381 0.381)
			(layers "F.Cu" "F.Mask" "F.Paste")
			(net "GND")
		)
		(pad "CF2" smd circle
			(at -0.050038 -3.41884)
			(size 0.3048 0.3048)
			(layers "F.Cu" "F.Mask" "F.Paste")
			(net "GND")
		)
		(pad "CF34" smd circle
			(at -0.050038 3.420364)
			(size 0.3048 0.3048)
			(layers "F.Cu" "F.Mask" "F.Paste")
			(net "GND")
		)
		(pad "CG1" smd oval
			(at -0.350012 -3.938524)
			(size 0.254 0.3302)
			(layers "F.Cu" "F.Mask" "F.Paste")
			(net "GND")
		)
		(pad "CG35" smd oval
			(at -0.350012 3.940048)
			(size 0.254 0.3302)
			(layers "F.Cu" "F.Mask" "F.Paste")
			(net "GND")
		)
		(pad "CH7" smd circle
			(at -0.39751 -2.12471)
			(size 0.381 0.381)
			(layers "F.Cu" "F.Mask" "F.Paste")
			(net "P5E_CPU1_P3_TX_BUF_DP<7>")
		)
		(pad "CH26" smd circle
			(at -0.39751 1.339342)
			(size 0.381 0.381)
			(layers "F.Cu" "F.Mask" "F.Paste")
			(net "P5E_CPU1_P3_RX_DP<7>")
		)
		(pad "CJ2" smd circle
			(at -0.649986 -3.41884)
			(size 0.3048 0.3048)
			(layers "F.Cu" "F.Mask" "F.Paste")
			(net "P5E_CPU1_P3_RX_BUF_DN<7>")
		)
		(pad "CJ34" smd circle
			(at -0.649986 3.420364)
			(size 0.3048 0.3048)
			(layers "F.Cu" "F.Mask" "F.Paste")
			(net "P5E_CPU1_P3_TX_C_DN<7>")
		)
		(pad "CK10" smd circle
			(at -0.797306 -1.431798)
			(size 0.381 0.381)
			(layers "F.Cu" "F.Mask" "F.Paste")
			(net "P5E_CPU1_P3_TX_BUF_DN<7>")
		)
		(pad "CK29" smd circle
			(at -0.797306 2.032254)
			(size 0.381 0.381)
			(layers "F.Cu" "F.Mask" "F.Paste")
			(net "P5E_CPU1_P3_RX_DN<7>")
		)
		(pad "CL1" smd oval
			(at -0.94996 -3.938524)
			(size 0.254 0.3302)
			(layers "F.Cu" "F.Mask" "F.Paste")
			(net "P5E_CPU1_P3_RX_BUF_DP<7>")
		)
		(pad "CL35" smd oval
			(at -0.94996 3.940048)
			(size 0.254 0.3302)
			(layers "F.Cu" "F.Mask" "F.Paste")
			(net "P5E_CPU1_P3_TX_C_DP<7>")
		)
		(pad "CM4" smd circle
			(at -1.197356 -2.817368)
			(size 0.381 0.381)
			(layers "F.Cu" "F.Mask" "F.Paste")
			(net "GND")
		)
		(pad "CM13" smd circle
			(at -1.197356 -0.79629)
			(size 0.3048 0.3048)
			(layers "F.Cu" "F.Mask" "F.Paste")
			(net "GND")
		)
		(pad "CM17" smd circle
			(at -1.197356 -0.296164)
			(size 0.3048 0.3048)
			(layers "F.Cu" "F.Mask" "F.Paste")
			(net "P1V8_CPU1_RT3_1A")
		)
		(pad "CM20" smd circle
			(at -1.197356 0.203708)
			(size 0.3048 0.3048)
			(layers "F.Cu" "F.Mask" "F.Paste")
			(net "P1V8_CPU1_RT3_1A")
		)
		(pad "CM22" smd circle
			(at -1.197356 0.703834)
			(size 0.3048 0.3048)
			(layers "F.Cu" "F.Mask" "F.Paste")
			(net "GND")
		)
		(pad "CM32" smd circle
			(at -1.197356 2.724912)
			(size 0.381 0.381)
			(layers "F.Cu" "F.Mask" "F.Paste")
			(net "GND")
		)
		(pad "CN2" smd circle
			(at -1.249934 -3.41884)
			(size 0.3048 0.3048)
			(layers "F.Cu" "F.Mask" "F.Paste")
			(net "GND")
		)
		(pad "CN34" smd circle
			(at -1.249934 3.420364)
			(size 0.3048 0.3048)
			(layers "F.Cu" "F.Mask" "F.Paste")
			(net "GND")
		)
		(pad "CP1" smd oval
			(at -1.549908 -3.938524)
			(size 0.254 0.3302)
			(layers "F.Cu" "F.Mask" "F.Paste")
			(net "GND")
		)
		(pad "CP35" smd oval
			(at -1.549908 3.940048)
			(size 0.254 0.3302)
			(layers "F.Cu" "F.Mask" "F.Paste")
			(net "GND")
		)
		(pad "CR7" smd circle
			(at -1.597406 -2.12471)
			(size 0.381 0.381)
			(layers "F.Cu" "F.Mask" "F.Paste")
			(net "P5E_CPU1_P3_TX_BUF_DP<6>")
		)
		(pad "CR26" smd circle
			(at -1.597406 1.339342)
			(size 0.381 0.381)
			(layers "F.Cu" "F.Mask" "F.Paste")
			(net "P5E_CPU1_P3_RX_DP<6>")
		)
		(pad "CT2" smd circle
			(at -1.849882 -3.41884)
			(size 0.3048 0.3048)
			(layers "F.Cu" "F.Mask" "F.Paste")
			(net "P5E_CPU1_P3_RX_BUF_DN<6>")
		)
		(pad "CT34" smd circle
			(at -1.849882 3.420364)
			(size 0.3048 0.3048)
			(layers "F.Cu" "F.Mask" "F.Paste")
			(net "P5E_CPU1_P3_TX_C_DN<6>")
		)
		(pad "CU10" smd circle
			(at -1.997456 -1.431798)
			(size 0.381 0.381)
			(layers "F.Cu" "F.Mask" "F.Paste")
			(net "P5E_CPU1_P3_TX_BUF_DN<6>")
		)
		(pad "CU29" smd circle
			(at -1.997456 2.032254)
			(size 0.381 0.381)
			(layers "F.Cu" "F.Mask" "F.Paste")
			(net "P5E_CPU1_P3_RX_DN<6>")
		)
		(pad "CV1" smd oval
			(at -2.15011 -3.938524)
			(size 0.254 0.3302)
			(layers "F.Cu" "F.Mask" "F.Paste")
			(net "P5E_CPU1_P3_RX_BUF_DP<6>")
		)
		(pad "CV35" smd oval
			(at -2.15011 3.940048)
			(size 0.254 0.3302)
			(layers "F.Cu" "F.Mask" "F.Paste")
			(net "P5E_CPU1_P3_TX_C_DP<6>")
		)
		(pad "CW4" smd circle
			(at -2.397506 -2.817368)
			(size 0.381 0.381)
			(layers "F.Cu" "F.Mask" "F.Paste")
			(net "GND")
		)
		(pad "CW13" smd circle
			(at -2.397506 -0.79629)
			(size 0.3048 0.3048)
			(layers "F.Cu" "F.Mask" "F.Paste")
			(net "GND")
		)
		(pad "CW17" smd circle
			(at -2.397506 -0.296164)
			(size 0.3048 0.3048)
			(layers "F.Cu" "F.Mask" "F.Paste")
			(net "P0V9_CPU1_RT_2D")
		)
		(pad "CW20" smd circle
			(at -2.397506 0.203708)
			(size 0.3048 0.3048)
			(layers "F.Cu" "F.Mask" "F.Paste")
			(net "P0V9_CPU1_RT_2D")
		)
		(pad "CW22" smd circle
			(at -2.397506 0.703834)
			(size 0.3048 0.3048)
			(layers "F.Cu" "F.Mask" "F.Paste")
			(net "GND")
		)
		(pad "CW32" smd circle
			(at -2.397506 2.724912)
			(size 0.381 0.381)
			(layers "F.Cu" "F.Mask" "F.Paste")
			(net "GND")
		)
		(pad "CY2" smd circle
			(at -2.450084 -3.41884)
			(size 0.3048 0.3048)
			(layers "F.Cu" "F.Mask" "F.Paste")
			(net "GND")
		)
		(pad "CY34" smd circle
			(at -2.450084 3.420364)
			(size 0.3048 0.3048)
			(layers "F.Cu" "F.Mask" "F.Paste")
			(net "GND")
		)
		(pad "D1" smd oval
			(at 10.450068 -3.938524)
			(size 0.254 0.3302)
			(layers "F.Cu" "F.Mask" "F.Paste")
			(net "NCF_CPU1_P3_GND")
		)
		(pad "D35" smd oval
			(at 10.450068 3.940048)
			(size 0.254 0.3302)
			(layers "F.Cu" "F.Mask" "F.Paste")
			(net "NCF_CPU1_P3_GND")
		)
		(pad "DA1" smd oval
			(at -2.750058 -3.938524)
			(size 0.254 0.3302)
			(layers "F.Cu" "F.Mask" "F.Paste")
			(net "GND")
		)
		(pad "DA35" smd oval
			(at -2.750058 3.940048)
			(size 0.254 0.3302)
			(layers "F.Cu" "F.Mask" "F.Paste")
			(net "GND")
		)
		(pad "DB7" smd circle
			(at -2.797302 -2.12471)
			(size 0.381 0.381)
			(layers "F.Cu" "F.Mask" "F.Paste")
			(net "P5E_CPU1_P3_TX_BUF_DP<5>")
		)
		(pad "DB26" smd circle
			(at -2.797302 1.339342)
			(size 0.381 0.381)
			(layers "F.Cu" "F.Mask" "F.Paste")
			(net "P5E_CPU1_P3_RX_DP<5>")
		)
		(pad "DC2" smd circle
			(at -3.050032 -3.41884)
			(size 0.3048 0.3048)
			(layers "F.Cu" "F.Mask" "F.Paste")
			(net "P5E_CPU1_P3_RX_BUF_DN<5>")
		)
		(pad "DC34" smd circle
			(at -3.050032 3.420364)
			(size 0.3048 0.3048)
			(layers "F.Cu" "F.Mask" "F.Paste")
			(net "P5E_CPU1_P3_TX_C_DN<5>")
		)
		(pad "DD10" smd circle
			(at -3.197352 -1.431798)
			(size 0.381 0.381)
			(layers "F.Cu" "F.Mask" "F.Paste")
			(net "P5E_CPU1_P3_TX_BUF_DN<5>")
		)
		(pad "DD29" smd circle
			(at -3.197352 2.032254)
			(size 0.381 0.381)
			(layers "F.Cu" "F.Mask" "F.Paste")
			(net "P5E_CPU1_P3_RX_DN<5>")
		)
		(pad "DE1" smd oval
			(at -3.350006 -3.938524)
			(size 0.254 0.3302)
			(layers "F.Cu" "F.Mask" "F.Paste")
			(net "P5E_CPU1_P3_RX_BUF_DP<5>")
		)
		(pad "DE35" smd oval
			(at -3.350006 3.940048)
			(size 0.254 0.3302)
			(layers "F.Cu" "F.Mask" "F.Paste")
			(net "P5E_CPU1_P3_TX_C_DP<5>")
		)
		(pad "DF4" smd circle
			(at -3.597402 -2.817368)
			(size 0.381 0.381)
			(layers "F.Cu" "F.Mask" "F.Paste")
			(net "GND")
		)
		(pad "DF13" smd circle
			(at -3.597402 -0.79629)
			(size 0.3048 0.3048)
			(layers "F.Cu" "F.Mask" "F.Paste")
			(net "GND")
		)
		(pad "DF17" smd circle
			(at -3.597402 -0.296164)
			(size 0.3048 0.3048)
			(layers "F.Cu" "F.Mask" "F.Paste")
			(net "P0V9_CPU1_RT3_2A_2D")
		)
		(pad "DF20" smd circle
			(at -3.597402 0.203708)
			(size 0.3048 0.3048)
			(layers "F.Cu" "F.Mask" "F.Paste")
			(net "P0V9_CPU1_RT3_2A_2D")
		)
		(pad "DF22" smd circle
			(at -3.597402 0.703834)
			(size 0.3048 0.3048)
			(layers "F.Cu" "F.Mask" "F.Paste")
			(net "GND")
		)
		(pad "DF32" smd circle
			(at -3.597402 2.724912)
			(size 0.381 0.381)
			(layers "F.Cu" "F.Mask" "F.Paste")
			(net "GND")
		)
		(pad "DG2" smd circle
			(at -3.64998 -3.41884)
			(size 0.3048 0.3048)
			(layers "F.Cu" "F.Mask" "F.Paste")
			(net "GND")
		)
		(pad "DG34" smd circle
			(at -3.64998 3.420364)
			(size 0.3048 0.3048)
			(layers "F.Cu" "F.Mask" "F.Paste")
			(net "GND")
		)
		(pad "DH1" smd oval
			(at -3.949954 -3.938524)
			(size 0.254 0.3302)
			(layers "F.Cu" "F.Mask" "F.Paste")
			(net "GND")
		)
		(pad "DH35" smd oval
			(at -3.949954 3.940048)
			(size 0.254 0.3302)
			(layers "F.Cu" "F.Mask" "F.Paste")
			(net "GND")
		)
		(pad "DJ7" smd circle
			(at -3.997452 -2.12471)
			(size 0.381 0.381)
			(layers "F.Cu" "F.Mask" "F.Paste")
			(net "P5E_CPU1_P3_TX_BUF_DP<4>")
		)
		(pad "DJ26" smd circle
			(at -3.997452 1.339342)
			(size 0.381 0.381)
			(layers "F.Cu" "F.Mask" "F.Paste")
			(net "P5E_CPU1_P3_RX_DP<4>")
		)
		(pad "DK2" smd circle
			(at -4.249928 -3.41884)
			(size 0.3048 0.3048)
			(layers "F.Cu" "F.Mask" "F.Paste")
			(net "P5E_CPU1_P3_RX_BUF_DN<4>")
		)
		(pad "DK34" smd circle
			(at -4.249928 3.420364)
			(size 0.3048 0.3048)
			(layers "F.Cu" "F.Mask" "F.Paste")
			(net "P5E_CPU1_P3_TX_C_DN<4>")
		)
		(pad "DL10" smd circle
			(at -4.397502 -1.431798)
			(size 0.381 0.381)
			(layers "F.Cu" "F.Mask" "F.Paste")
			(net "P5E_CPU1_P3_TX_BUF_DN<4>")
		)
		(pad "DL29" smd circle
			(at -4.397502 2.032254)
			(size 0.381 0.381)
			(layers "F.Cu" "F.Mask" "F.Paste")
			(net "P5E_CPU1_P3_RX_DN<4>")
		)
		(pad "DM1" smd oval
			(at -4.549902 -3.938524)
			(size 0.254 0.3302)
			(layers "F.Cu" "F.Mask" "F.Paste")
			(net "P5E_CPU1_P3_RX_BUF_DP<4>")
		)
		(pad "DM35" smd oval
			(at -4.549902 3.940048)
			(size 0.254 0.3302)
			(layers "F.Cu" "F.Mask" "F.Paste")
			(net "P5E_CPU1_P3_TX_C_DP<4>")
		)
		(pad "DN4" smd circle
			(at -4.797298 -2.817368)
			(size 0.381 0.381)
			(layers "F.Cu" "F.Mask" "F.Paste")
			(net "GND")
		)
		(pad "DN13" smd circle
			(at -4.797298 -0.79629)
			(size 0.3048 0.3048)
			(layers "F.Cu" "F.Mask" "F.Paste")
			(net "GND")
		)
		(pad "DN17" smd circle
			(at -4.797298 -0.296164)
			(size 0.3048 0.3048)
			(layers "F.Cu" "F.Mask" "F.Paste")
			(net "P0V9_CPU1_RT3_2A")
		)
		(pad "DN20" smd circle
			(at -4.797298 0.203708)
			(size 0.3048 0.3048)
			(layers "F.Cu" "F.Mask" "F.Paste")
			(net "P0V9_CPU1_RT3_2A")
		)
		(pad "DN22" smd circle
			(at -4.797298 0.703834)
			(size 0.3048 0.3048)
			(layers "F.Cu" "F.Mask" "F.Paste")
			(net "GND")
		)
		(pad "DN32" smd circle
			(at -4.797298 2.724912)
			(size 0.381 0.381)
			(layers "F.Cu" "F.Mask" "F.Paste")
			(net "GND")
		)
		(pad "DP2" smd circle
			(at -4.849876 -3.41884)
			(size 0.3048 0.3048)
			(layers "F.Cu" "F.Mask" "F.Paste")
			(net "GND")
		)
		(pad "DP34" smd circle
			(at -4.849876 3.420364)
			(size 0.3048 0.3048)
			(layers "F.Cu" "F.Mask" "F.Paste")
			(net "GND")
		)
		(pad "DR1" smd oval
			(at -5.150104 -3.938524)
			(size 0.254 0.3302)
			(layers "F.Cu" "F.Mask" "F.Paste")
			(net "GND")
		)
		(pad "DR35" smd oval
			(at -5.150104 3.940048)
			(size 0.254 0.3302)
			(layers "F.Cu" "F.Mask" "F.Paste")
			(net "GND")
		)
		(pad "DT7" smd circle
			(at -5.197348 -2.12471)
			(size 0.381 0.381)
			(layers "F.Cu" "F.Mask" "F.Paste")
			(net "P5E_CPU1_P3_TX_BUF_DP<3>")
		)
		(pad "DT26" smd circle
			(at -5.197348 1.339342)
			(size 0.381 0.381)
			(layers "F.Cu" "F.Mask" "F.Paste")
			(net "P5E_CPU1_P3_RX_DP<3>")
		)
		(pad "DU2" smd circle
			(at -5.450078 -3.41884)
			(size 0.3048 0.3048)
			(layers "F.Cu" "F.Mask" "F.Paste")
			(net "P5E_CPU1_P3_RX_BUF_DN<3>")
		)
		(pad "DU34" smd circle
			(at -5.450078 3.420364)
			(size 0.3048 0.3048)
			(layers "F.Cu" "F.Mask" "F.Paste")
			(net "P5E_CPU1_P3_TX_C_DN<3>")
		)
		(pad "DV10" smd circle
			(at -5.597398 -1.431798)
			(size 0.381 0.381)
			(layers "F.Cu" "F.Mask" "F.Paste")
			(net "P5E_CPU1_P3_TX_BUF_DN<3>")
		)
		(pad "DV29" smd circle
			(at -5.597398 2.032254)
			(size 0.381 0.381)
			(layers "F.Cu" "F.Mask" "F.Paste")
			(net "P5E_CPU1_P3_RX_DN<3>")
		)
		(pad "DW1" smd oval
			(at -5.750052 -3.938524)
			(size 0.254 0.3302)
			(layers "F.Cu" "F.Mask" "F.Paste")
			(net "P5E_CPU1_P3_RX_BUF_DP<3>")
		)
		(pad "DW35" smd oval
			(at -5.750052 3.940048)
			(size 0.254 0.3302)
			(layers "F.Cu" "F.Mask" "F.Paste")
			(net "P5E_CPU1_P3_TX_C_DP<3>")
		)
		(pad "DY4" smd circle
			(at -5.997448 -2.817368)
			(size 0.381 0.381)
			(layers "F.Cu" "F.Mask" "F.Paste")
			(net "GND")
		)
		(pad "DY13" smd circle
			(at -5.997448 -0.79629)
			(size 0.3048 0.3048)
			(layers "F.Cu" "F.Mask" "F.Paste")
			(net "GND")
		)
		(pad "DY17" smd circle
			(at -5.997448 -0.296164)
			(size 0.3048 0.3048)
			(layers "F.Cu" "F.Mask" "F.Paste")
			(net "P0V9_CPU1_RT3_2A")
		)
		(pad "DY20" smd circle
			(at -5.997448 0.203708)
			(size 0.3048 0.3048)
			(layers "F.Cu" "F.Mask" "F.Paste")
			(net "P0V9_CPU1_RT3_2A")
		)
		(pad "DY22" smd circle
			(at -5.997448 0.703834)
			(size 0.3048 0.3048)
			(layers "F.Cu" "F.Mask" "F.Paste")
			(net "GND")
		)
	)
)
